FILE_TYPE = CONNECTIVITY;
{Allegro Design Entry HDL 17.2-2016 S081 (4005846) 1/11/2022}
"PAGE_NUMBER" = 143;
0"NC";
1"P3V3_AUX\g";
2"P3V3_AUX\g";
3"P3V3_AUX\g";
4"P3V3_AUX\g";
5"P3V3_AUX\g";
6"P3V3_AUX\g";
7"P3V3_AUX\g";
8"P3V3_AUX\g";
9"P3V3_AUX\g";
10"P3V3_AUX\g";
11"P3V3_AUX\g";
12"P3V3_AUX\g";
13"P3V3_AUX\g";
14"P3V3_AUX\g";
15"P3V3_AUX\g";
16"P3V3_AUX\g";
17"P3V3_AUX\g";
18"P3V3_AUX\g";
19"P3V3_AUX\g";
20"P3V3_AUX\g";
21"P3V3_AUX\g";
22"P3V3_AUX\g";
23"P3V3_AUX\g";
24"P3V3_AUX\g";
25"GND\g";
26"GND\g";
27"GND\g";
28"GND\g";
29"GND\g";
30"GND\g";
31"GND\g";
32"GND\g";
33"GND\g";
34"GND\g";
35"GND\g";
36"GND\g";
37"GND\g";
38"GND\g";
39"GND\g";
40"GND\g";
41"GND\g";
42"GND\g";
43"GND\g";
44"GND\g";
45"GND\g";
46"GND\g";
47"GND\g";
48"GND\g";
49"GND\g";
50"GND\g";
51"GND\g";
52"GND\g";
53"GND\g";
54"GND\g";
55"GND\g";
56"GND\g";
57"GPU_3V3IO_RSVD0_FFU_ISO";
58"GPU_3V3IO_RSVD3_FFU";
59"PRSNT_CABLE_GPU_A2_N";
60"GPU_3V3IO_RSVD5_FFU";
61"PRSNT_CABLE_GPU_A1_ISO_N";
62"PRSNT_CABLE_GPU_B3_N";
63"PRSNT_CABLE_GPU_B3_ISO_N";
64"PRSNT_CABLE_GPU_A1_N";
65"PRSNT_CABLE_GPU_A1";
66"PRSNT_CABLE_GPU_A2_ISO_N";
67"PRSNT_CABLE_GPU_A2";
68"SWB_HSC_PWRGD_N";
69"GPU_3V3IO_RSVD0_FFU";
70"GPU_3V3IO_RSVD0_FFU_N";
71"GPU_3V3IO_RSVD1_FFU_ISO";
72"GPU_3V3IO_RSVD1_FFU";
73"GPU_3V3IO_RSVD3_FFU_ISO";
74"GPU_3V3IO_RSVD5_FFU_ISO";
75"GPU_3V3IO_RSVD5_FFU_N";
76"GPU_3V3IO_RSVD3_FFU_N";
77"GPU_3V3IO_RSVD1_FFU_N";
78"PRSNT_CABLE_GPU_B3";
79"SWB_HSC_PWRGD";
80"SWB_HSC_PWRGD_ISO";
%"UNIVERSAL_GND"
"1","(-1125,3125)","0","logical_power","I10";
;
CDS_LIB"logical_power"
HDL_POWER"GND";
"A"52;
%"Q_RES"
"2","(-1050,-275)","0","pure_quanta","I100";
;
PART_NUMBER"CS24702JB10"
WATTAGE"1/16W"
MATERIAL"CHIP"
TOLERANCE"5%"
VALUE"4.7K"
PACK_TYPE"0402LF"
$LOCATION"R4155"
CDS_LIB"pure_quanta"
CDS_LOCATION"R4155"
$SEC"1"
CDS_SEC"1";
"A"
$PN"1"22;
"B"
$PN"2"65;
%"Q_RES"
"2","(100,-150)","0","pure_quanta","I101";
;
PART_NUMBER"CS24702JB10"
WATTAGE"1/16W"
MATERIAL"CHIP"
PACK_TYPE"0402LF"
TOLERANCE"5%"
VALUE"4.7K"
$LOCATION"R4156"
CDS_LIB"pure_quanta"
CDS_LOCATION"R4156"
$SEC"1"
CDS_SEC"1";
"A"
$PN"1"3;
"B"
$PN"2"61;
%"UNIVERSAL_POWER"
"1","(100,75)","0","logical_power","I103";
;
HDL_POWER"P3V3_AUX"
CDS_LIB"logical_power";
"A"3;
%"UNIVERSAL_GND"
"1","(875,-825)","0","logical_power","I104";
;
CDS_LIB"logical_power"
HDL_POWER"GND";
"A"39;
%"Q_CAP"
"1","(875,-625)","0","pure_quanta","I105";
;
PART_NUMBER"TMP_QCH21006JB10"
TOLERANCE"5%"
MATERIAL"EMPTY"
VOLTAGE"50V"
VALUE"1000PF"
PACK_TYPE"0402"
$LOCATION"C2270"
CDS_LIB"pure_quanta"
CDS_LOCATION"C2270"
$SEC"1"
CDS_SEC"1";
"B"
$PN"2"39;
"A"
$PN"1"61;
%"UNIVERSAL_GND"
"1","(100,-950)","0","logical_power","I106";
;
CDS_LIB"logical_power"
HDL_POWER"GND";
"A"40;
%"MOSFET_NCH_DUAL"
"2","(50,-575)","0","pure_quanta","I107";
;
PART_NUMBER"BAM138K0003"
VALUE"PJT138K"
MATERIAL"IC"
PART_TYPE"SMLF"
$LOCATION"Q134"
CDS_LMAN_SYM_OUTLINE"-150,150,150,-150"
NEEDS_NO_SIZE"TRUE"
CDS_LIB"pure_quanta"
CDS_LOCATION"Q134"
$SEC"2"
CDS_SEC"2";
"S2"
$PN"4"40;
"G2"
$PN"5"65;
"D2"
$PN"3"61;
%"UNIVERSAL_POWER"
"1","(-1050,-50)","0","logical_power","I108";
;
HDL_POWER"P3V3_AUX"
CDS_LIB"logical_power";
"A"22;
%"UNIVERSAL_GND"
"1","(-1050,-1250)","0","logical_power","I109";
;
CDS_LIB"logical_power"
HDL_POWER"GND";
"A"41;
%"MOSFET_NCH_DUAL"
"1","(-1175,3500)","0","pure_quanta","I11";
;
PART_NUMBER"BAM138K0003"
MATERIAL"IC"
VALUE"PJT138K"
PART_TYPE"SMLF"
$LOCATION"Q128"
CDS_LIB"pure_quanta"
NEEDS_NO_SIZE"TRUE"
CDS_LMAN_SYM_OUTLINE"-150,150,150,-150"
CDS_LOCATION"Q128"
$SEC"1"
CDS_SEC"1";
"D1"
$PN"6"70;
"G1"
$PN"2"69;
"S1"
$PN"1"52;
%"UNIVERSAL_POWER"
"1","(-2225,-400)","0","logical_power","I110";
;
HDL_POWER"P3V3_AUX"
CDS_LIB"logical_power";
"A"2;
%"Q_RES"
"2","(-2200,-1125)","0","pure_quanta","I113";
;
PART_NUMBER"CS41002FB09"
TOLERANCE"1%"
VALUE"100K"
PACK_TYPE"0402LF"
MATERIAL"EMPTY"
WATTAGE"1/16W"
$LOCATION"R4154"
CDS_LIB"pure_quanta"
CDS_LOCATION"R4154"
$SEC"1"
CDS_SEC"1";
"A"
$PN"1"64;
"B"
$PN"2"35;
%"UNIVERSAL_GND"
"1","(-2200,-1400)","0","logical_power","I114";
;
CDS_LIB"logical_power"
HDL_POWER"GND";
"A"35;
%"Q_RES"
"2","(4650,225)","0","pure_quanta","I116";
;
PART_NUMBER"CS24702JB10"
WATTAGE"1/16W"
PACK_TYPE"0402LF"
VALUE"4.7K"
TOLERANCE"5%"
MATERIAL"CHIP"
$LOCATION"R4561"
CDS_LIB"pure_quanta"
CDS_LOCATION"R4561"
$SEC"1"
CDS_SEC"1";
"A"
$PN"1"9;
"B"
$PN"2"80;
%"Q_CAP"
"1","(5425,-250)","0","pure_quanta","I118";
;
PART_NUMBER"TMP_QCH21006JB10"
MATERIAL"EMPTY"
VALUE"1000PF"
PACK_TYPE"0402"
TOLERANCE"5%"
VOLTAGE"50V"
$LOCATION"C2343"
CDS_LIB"pure_quanta"
CDS_LOCATION"C2343"
$SEC"1"
CDS_SEC"1";
"B"
$PN"2"25;
"A"
$PN"1"80;
%"UNIVERSAL_GND"
"1","(5425,-450)","0","logical_power","I119";
;
HDL_POWER"GND"
CDS_LIB"logical_power";
"A"25;
%"UNIVERSAL_POWER"
"1","(-2300,3975)","0","logical_power","I12";
;
HDL_POWER"P3V3_AUX"
CDS_LIB"logical_power";
"A"13;
%"UNIVERSAL_POWER"
"1","(4650,450)","0","logical_power","I120";
;
HDL_POWER"P3V3_AUX"
CDS_LIB"logical_power";
"A"9;
%"MOSFET_NCH_DUAL"
"2","(4600,-200)","0","pure_quanta","I121";
;
PART_NUMBER"BAM138K0003"
MATERIAL"IC"
VALUE"PJT138K"
PART_TYPE"SMLF"
LOCATION"Q146"
CDS_LIB"pure_quanta"
NEEDS_NO_SIZE"TRUE"
CDS_LMAN_SYM_OUTLINE"-150,150,150,-150"
$SEC"2"
CDS_SEC"2";
"S2"
$PN"4"26;
"G2"
$PN"5"68;
"D2"
$PN"3"80;
%"UNIVERSAL_GND"
"1","(4650,-575)","0","logical_power","I122";
;
HDL_POWER"GND"
CDS_LIB"logical_power";
"A"26;
%"UNIVERSAL_POWER"
"1","(3500,325)","0","logical_power","I123";
;
HDL_POWER"P3V3_AUX"
CDS_LIB"logical_power";
"A"5;
%"Q_RES"
"2","(3500,100)","0","pure_quanta","I124";
;
PART_NUMBER"CS24702JB10"
PACK_TYPE"0402LF"
WATTAGE"1/16W"
VALUE"4.7K"
TOLERANCE"5%"
MATERIAL"CHIP"
$LOCATION"R4560"
CDS_LIB"pure_quanta"
CDS_LOCATION"R4560"
$SEC"1"
CDS_SEC"1";
"A"
$PN"1"5;
"B"
$PN"2"68;
%"UNIVERSAL_GND"
"1","(3500,-875)","0","logical_power","I125";
;
HDL_POWER"GND"
CDS_LIB"logical_power";
"A"27;
%"MOSFET_NCH_DUAL"
"1","(3450,-500)","0","pure_quanta","I126";
;
PART_NUMBER"BAM138K0003"
VALUE"PJT138K"
MATERIAL"IC"
PART_TYPE"SMLF"
$LOCATION"Q146"
CDS_LMAN_SYM_OUTLINE"-150,150,150,-150"
NEEDS_NO_SIZE"TRUE"
CDS_LIB"pure_quanta"
CDS_LOCATION"Q146"
$SEC"1"
CDS_SEC"1";
"D1"
$PN"6"68;
"G1"
$PN"2"79;
"S1"
$PN"1"27;
%"UNIVERSAL_POWER"
"1","(2325,-25)","0","logical_power","I127";
;
HDL_POWER"P3V3_AUX"
CDS_LIB"logical_power";
"A"10;
%"Q_RES"
"2","(2350,-750)","0","pure_quanta","I129";
;
PART_NUMBER"CS41002FB09"
VALUE"100K"
PACK_TYPE"0402LF"
WATTAGE"1/16W"
TOLERANCE"1%"
MATERIAL"CHIP"
$LOCATION"R4559"
CDS_LIB"pure_quanta"
CDS_LOCATION"R4559"
$SEC"1"
CDS_SEC"1";
"A"
$PN"1"79;
"B"
$PN"2"28;
%"Q_RES"
"2","(-2300,3725)","0","pure_quanta","I13";
;
PART_NUMBER"CS35492FB03"
VALUE"54.9K"
TOLERANCE"1%"
WATTAGE"1/16W"
PACK_TYPE"0402LF"
MATERIAL"EMPTY"
$LOCATION"R4119"
CDS_LIB"pure_quanta"
CDS_LOCATION"R4119"
$SEC"1"
CDS_SEC"1";
"A"
$PN"1"13;
"B"
$PN"2"69;
%"UNIVERSAL_GND"
"1","(2350,-1025)","0","logical_power","I130";
;
HDL_POWER"GND"
CDS_LIB"logical_power";
"A"28;
%"Q_RES"
"2","(2325,-275)","0","pure_quanta","I132";
;
PART_NUMBER"CS41002FB09"
PACK_TYPE"0402LF"
VALUE"100K"
WATTAGE"1/16W"
MATERIAL"EMPTY"
TOLERANCE"1%"
$LOCATION"R4562"
CDS_LIB"pure_quanta"
CDS_LOCATION"R4562"
$SEC"1"
CDS_SEC"1";
"A"
$PN"1"10;
"B"
$PN"2"79;
%"Q_RES"
"1","(-775,175)","0","pure_quanta","I136";
;
PART_NUMBER"CS00002JB13"
WATTAGE"1/16W"
PACK_TYPE"0402LF"
VALUE"0"
TOLERANCE"5%"
MATERIAL"EMPTY"
$LOCATION"R4574"
CDS_LIB"pure_quanta"
CDS_LOCATION"R4574"
$SEC"1"
CDS_SEC"1";
"B"
$PN"2"61;
"A"
$PN"1"64;
%"Q_RES"
"1","(3800,4775)","0","pure_quanta","I137";
;
PART_NUMBER"CS00002JB13"
VALUE"0"
WATTAGE"1/16W"
PACK_TYPE"0402LF"
TOLERANCE"5%"
MATERIAL"EMPTY"
$LOCATION"R4577"
CDS_LIB"pure_quanta"
CDS_LOCATION"R4577"
$SEC"1"
CDS_SEC"1";
"B"
$PN"2"73;
"A"
$PN"1"58;
%"Q_RES"
"1","(3850,3400)","0","pure_quanta","I138";
;
PART_NUMBER"CS00002JB13"
MATERIAL"EMPTY"
VALUE"0"
TOLERANCE"5%"
PACK_TYPE"0402LF"
WATTAGE"1/16W"
$LOCATION"R4578"
CDS_LIB"pure_quanta"
CDS_LOCATION"R4578"
$SEC"1"
CDS_SEC"1";
"B"
$PN"2"66;
"A"
$PN"1"59;
%"Q_RES"
"1","(3775,1950)","0","pure_quanta","I139";
;
PART_NUMBER"CS00002JB13"
TOLERANCE"5%"
WATTAGE"1/16W"
PACK_TYPE"0402LF"
MATERIAL"EMPTY"
VALUE"0"
$LOCATION"R4576"
CDS_LIB"pure_quanta"
CDS_LOCATION"R4576"
$SEC"1"
CDS_SEC"1";
"B"
$PN"2"74;
"A"
$PN"1"60;
%"Q_RES"
"2","(-2275,3250)","0","pure_quanta","I14";
;
PART_NUMBER"CS41002FB09"
MATERIAL"EMPTY"
WATTAGE"1/16W"
TOLERANCE"1%"
VALUE"100K"
PACK_TYPE"0402LF"
$LOCATION"R4120"
CDS_LIB"pure_quanta"
CDS_LOCATION"R4120"
$SEC"1"
CDS_SEC"1";
"A"
$PN"1"69;
"B"
$PN"2"38;
%"Q_RES"
"1","(-850,1650)","0","pure_quanta","I140";
;
PART_NUMBER"CS00002JB13"
WATTAGE"1/16W"
PACK_TYPE"0402LF"
VALUE"0"
MATERIAL"EMPTY"
TOLERANCE"5%"
$LOCATION"R4573"
CDS_LIB"pure_quanta"
CDS_LOCATION"R4573"
$SEC"1"
CDS_SEC"1";
"B"
$PN"2"63;
"A"
$PN"1"62;
%"Q_RES"
"1","(-850,3100)","0","pure_quanta","I141";
;
PART_NUMBER"CS00002JB13"
TOLERANCE"5%"
VALUE"0"
WATTAGE"1/16W"
MATERIAL"EMPTY"
PACK_TYPE"0402LF"
$LOCATION"R4572"
CDS_LIB"pure_quanta"
CDS_LOCATION"R4572"
$SEC"1"
CDS_SEC"1";
"B"
$PN"2"71;
"A"
$PN"1"72;
%"Q_RES"
"1","(-725,4550)","0","pure_quanta","I142";
;
PART_NUMBER"CS00002JB13"
PACK_TYPE"0402LF"
VALUE"0"
MATERIAL"EMPTY"
TOLERANCE"5%"
WATTAGE"1/16W"
$LOCATION"R4575"
CDS_LIB"pure_quanta"
CDS_LOCATION"R4575"
$SEC"1"
CDS_SEC"1";
"B"
$PN"2"57;
"A"
$PN"1"69;
%"Q_RES"
"2","(-2300,900)","0","pure_quanta","I143";
;
PART_NUMBER"CS31002FB08"
VALUE"10K"
PACK_TYPE"0402LF"
MATERIAL"CHIP"
TOLERANCE"1%"
WATTAGE"1/16W"
LOCATION"R4121"
CDS_LIB"pure_quanta"
$SEC"1"
CDS_SEC"1";
"A"
$PN"1"19;
"B"
$PN"2"62;
%"Q_RES"
"2","(2350,2650)","0","pure_quanta","I144";
;
PART_NUMBER"CS31002FB08"
TOLERANCE"1%"
MATERIAL"CHIP"
PACK_TYPE"0402LF"
WATTAGE"1/16W"
VALUE"10K"
LOCATION"R4135"
CDS_LIB"pure_quanta"
$SEC"1"
CDS_SEC"1";
"A"
$PN"1"1;
"B"
$PN"2"59;
%"Q_RES"
"2","(-2225,-650)","0","pure_quanta","I145";
;
PART_NUMBER"CS31002FB08"
VALUE"10K"
TOLERANCE"1%"
WATTAGE"1/16W"
PACK_TYPE"0402LF"
MATERIAL"CHIP"
LOCATION"R4153"
CDS_LIB"pure_quanta"
$SEC"1"
CDS_SEC"1";
"A"
$PN"1"2;
"B"
$PN"2"64;
%"UNIVERSAL_GND"
"1","(-2275,2975)","0","logical_power","I16";
;
CDS_LIB"logical_power"
HDL_POWER"GND";
"A"38;
%"MOSFET_NCH_DUAL"
"2","(0,2425)","0","pure_quanta","I19";
;
PART_NUMBER"BAM138K0003"
MATERIAL"IC"
PART_TYPE"SMLF"
VALUE"PJT138K"
$LOCATION"Q131"
CDS_LMAN_SYM_OUTLINE"-150,150,150,-150"
NEEDS_NO_SIZE"TRUE"
CDS_LIB"pure_quanta"
CDS_LOCATION"Q131"
$SEC"2"
CDS_SEC"2";
"S2"
$PN"4"54;
"G2"
$PN"5"77;
"D2"
$PN"3"71;
%"Q_CAP"
"1","(800,3750)","0","pure_quanta","I2";
;
PART_NUMBER"TMP_QCH21006JB10"
PACK_TYPE"0402"
VOLTAGE"50V"
MATERIAL"EMPTY"
TOLERANCE"5%"
VALUE"1000PF"
$LOCATION"C2264"
CDS_LIB"pure_quanta"
CDS_LOCATION"C2264"
$SEC"1"
CDS_SEC"1";
"B"
$PN"2"56;
"A"
$PN"1"57;
%"UNIVERSAL_POWER"
"1","(50,3075)","0","logical_power","I20";
;
HDL_POWER"P3V3_AUX"
CDS_LIB"logical_power";
"A"18;
%"Q_RES"
"2","(50,2850)","0","pure_quanta","I21";
;
PART_NUMBER"CS24702JB10"
PACK_TYPE"0402LF"
VALUE"4.7K"
TOLERANCE"5%"
WATTAGE"1/16W"
MATERIAL"CHIP"
$LOCATION"R4130"
CDS_LIB"pure_quanta"
CDS_LOCATION"R4130"
$SEC"1"
CDS_SEC"1";
"A"
$PN"1"18;
"B"
$PN"2"71;
%"Q_CAP"
"1","(825,2375)","0","pure_quanta","I23";
;
PART_NUMBER"TMP_QCH21006JB10"
PACK_TYPE"0402"
VALUE"1000PF"
VOLTAGE"50V"
TOLERANCE"5%"
MATERIAL"EMPTY"
$LOCATION"C2266"
CDS_LIB"pure_quanta"
CDS_LOCATION"C2266"
$SEC"1"
CDS_SEC"1";
"B"
$PN"2"55;
"A"
$PN"1"71;
%"UNIVERSAL_GND"
"1","(825,2175)","0","logical_power","I24";
;
CDS_LIB"logical_power"
HDL_POWER"GND";
"A"55;
%"UNIVERSAL_GND"
"1","(50,2050)","0","logical_power","I25";
;
CDS_LIB"logical_power"
HDL_POWER"GND";
"A"54;
%"UNIVERSAL_POWER"
"1","(-1100,2950)","0","logical_power","I26";
;
HDL_POWER"P3V3_AUX"
CDS_LIB"logical_power";
"A"4;
%"Q_RES"
"2","(-1100,2725)","0","pure_quanta","I27";
;
PART_NUMBER"CS24702JB10"
MATERIAL"CHIP"
WATTAGE"1/16W"
PACK_TYPE"0402LF"
TOLERANCE"5%"
VALUE"4.7K"
$LOCATION"R4127"
CDS_LIB"pure_quanta"
CDS_LOCATION"R4127"
$SEC"1"
CDS_SEC"1";
"A"
$PN"1"4;
"B"
$PN"2"77;
%"UNIVERSAL_GND"
"1","(-1100,1750)","0","logical_power","I28";
;
CDS_LIB"logical_power"
HDL_POWER"GND";
"A"51;
%"MOSFET_NCH_DUAL"
"1","(-1150,2125)","0","pure_quanta","I29";
;
PART_NUMBER"BAM138K0003"
PART_TYPE"SMLF"
MATERIAL"IC"
VALUE"PJT138K"
LOCATION"Q131"
CDS_LIB"pure_quanta"
NEEDS_NO_SIZE"TRUE"
CDS_LMAN_SYM_OUTLINE"-150,150,150,-150"
$SEC"1"
CDS_SEC"1";
"D1"
$PN"6"77;
"G1"
$PN"2"72;
"S1"
$PN"1"51;
%"UNIVERSAL_GND"
"1","(800,3550)","0","logical_power","I3";
;
CDS_LIB"logical_power"
HDL_POWER"GND";
"A"56;
%"UNIVERSAL_POWER"
"1","(-2275,2600)","0","logical_power","I30";
;
HDL_POWER"P3V3_AUX"
CDS_LIB"logical_power";
"A"20;
%"Q_RES"
"2","(-2275,2350)","0","pure_quanta","I31";
;
PART_NUMBER"CS35492FB03"
WATTAGE"1/16W"
MATERIAL"EMPTY"
PACK_TYPE"0402LF"
TOLERANCE"1%"
VALUE"54.9K"
$LOCATION"R4123"
CDS_LIB"pure_quanta"
CDS_LOCATION"R4123"
$SEC"1"
CDS_SEC"1";
"A"
$PN"1"20;
"B"
$PN"2"72;
%"Q_RES"
"2","(-2250,1875)","0","pure_quanta","I32";
;
PART_NUMBER"CS41002FB09"
MATERIAL"EMPTY"
TOLERANCE"1%"
VALUE"100K"
PACK_TYPE"0402LF"
WATTAGE"1/16W"
$LOCATION"R4124"
CDS_LIB"pure_quanta"
CDS_LOCATION"R4124"
$SEC"1"
CDS_SEC"1";
"A"
$PN"1"72;
"B"
$PN"2"37;
%"UNIVERSAL_GND"
"1","(-2250,1600)","0","logical_power","I34";
;
CDS_LIB"logical_power"
HDL_POWER"GND";
"A"37;
%"MOSFET_NCH_DUAL"
"2","(-25,975)","0","pure_quanta","I35";
;
PART_NUMBER"BAM138K0003"
PART_TYPE"SMLF"
VALUE"PJT138K"
MATERIAL"IC"
$LOCATION"Q132"
CDS_LIB"pure_quanta"
NEEDS_NO_SIZE"TRUE"
CDS_LMAN_SYM_OUTLINE"-150,150,150,-150"
CDS_LOCATION"Q132"
$SEC"2"
CDS_SEC"2";
"S2"
$PN"4"43;
"G2"
$PN"5"78;
"D2"
$PN"3"63;
%"Q_RES"
"2","(25,1400)","0","pure_quanta","I36";
;
PART_NUMBER"CS24702JB10"
MATERIAL"CHIP"
VALUE"4.7K"
WATTAGE"1/16W"
TOLERANCE"5%"
PACK_TYPE"0402LF"
$LOCATION"R4129"
CDS_LIB"pure_quanta"
CDS_LOCATION"R4129"
$SEC"1"
CDS_SEC"1";
"A"
$PN"1"21;
"B"
$PN"2"63;
%"UNIVERSAL_POWER"
"1","(25,1625)","0","logical_power","I37";
;
HDL_POWER"P3V3_AUX"
CDS_LIB"logical_power";
"A"21;
%"UNIVERSAL_POWER"
"1","(-1125,1500)","0","logical_power","I38";
;
HDL_POWER"P3V3_AUX"
CDS_LIB"logical_power";
"A"24;
%"UNIVERSAL_POWER"
"1","(25,4450)","0","logical_power","I4";
;
HDL_POWER"P3V3_AUX"
CDS_LIB"logical_power";
"A"17;
%"Q_CAP"
"1","(800,925)","0","pure_quanta","I40";
;
PART_NUMBER"TMP_QCH21006JB10"
PACK_TYPE"0402"
MATERIAL"EMPTY"
TOLERANCE"5%"
VOLTAGE"50V"
VALUE"1000PF"
$LOCATION"C2265"
CDS_LIB"pure_quanta"
CDS_LOCATION"C2265"
$SEC"1"
CDS_SEC"1";
"B"
$PN"2"44;
"A"
$PN"1"63;
%"UNIVERSAL_GND"
"1","(800,725)","0","logical_power","I41";
;
HDL_POWER"GND"
CDS_LIB"logical_power";
"A"44;
%"UNIVERSAL_GND"
"1","(25,600)","0","logical_power","I42";
;
HDL_POWER"GND"
CDS_LIB"logical_power";
"A"43;
%"Q_RES"
"2","(-1125,1275)","0","pure_quanta","I43";
;
PART_NUMBER"CS24702JB10"
WATTAGE"1/16W"
TOLERANCE"5%"
MATERIAL"CHIP"
PACK_TYPE"0402LF"
VALUE"4.7K"
$LOCATION"R4126"
CDS_LIB"pure_quanta"
CDS_LOCATION"R4126"
$SEC"1"
CDS_SEC"1";
"A"
$PN"1"24;
"B"
$PN"2"78;
%"MOSFET_NCH_DUAL"
"1","(-1175,675)","0","pure_quanta","I44";
;
PART_NUMBER"BAM138K0003"
MATERIAL"IC"
PART_TYPE"SMLF"
VALUE"PJT138K"
LOCATION"Q132"
CDS_LMAN_SYM_OUTLINE"-150,150,150,-150"
NEEDS_NO_SIZE"TRUE"
CDS_LIB"pure_quanta"
$SEC"1"
CDS_SEC"1";
"D1"
$PN"6"78;
"G1"
$PN"2"62;
"S1"
$PN"1"42;
%"UNIVERSAL_GND"
"1","(-1125,300)","0","logical_power","I45";
;
HDL_POWER"GND"
CDS_LIB"logical_power";
"A"42;
%"UNIVERSAL_POWER"
"1","(-2300,1150)","0","logical_power","I46";
;
HDL_POWER"P3V3_AUX"
CDS_LIB"logical_power";
"A"19;
%"Q_RES"
"2","(-2275,425)","0","pure_quanta","I49";
;
PART_NUMBER"CS41002FB09"
VALUE"100K"
PACK_TYPE"0402LF"
WATTAGE"1/16W"
TOLERANCE"1%"
MATERIAL"EMPTY"
$LOCATION"R4122"
CDS_LIB"pure_quanta"
CDS_LOCATION"R4122"
$SEC"1"
CDS_SEC"1";
"A"
$PN"1"62;
"B"
$PN"2"36;
%"Q_RES"
"2","(25,4225)","0","pure_quanta","I5";
;
PART_NUMBER"CS24702JB10"
TOLERANCE"5%"
WATTAGE"1/16W"
VALUE"4.7K"
MATERIAL"CHIP"
PACK_TYPE"0402LF"
$LOCATION"R4128"
CDS_LIB"pure_quanta"
CDS_LOCATION"R4128"
$SEC"1"
CDS_SEC"1";
"A"
$PN"1"17;
"B"
$PN"2"57;
%"UNIVERSAL_GND"
"1","(-2275,150)","0","logical_power","I50";
;
HDL_POWER"GND"
CDS_LIB"logical_power";
"A"36;
%"UNIVERSAL_POWER"
"1","(4650,4750)","0","logical_power","I51";
;
HDL_POWER"P3V3_AUX"
CDS_LIB"logical_power";
"A"15;
%"Q_RES"
"2","(4650,4525)","0","pure_quanta","I52";
;
PART_NUMBER"CS24702JB10"
VALUE"4.7K"
WATTAGE"1/16W"
TOLERANCE"5%"
PACK_TYPE"0402LF"
MATERIAL"CHIP"
$LOCATION"R4140"
CDS_LIB"pure_quanta"
CDS_LOCATION"R4140"
$SEC"1"
CDS_SEC"1";
"A"
$PN"1"15;
"B"
$PN"2"73;
%"Q_CAP"
"1","(5425,4050)","0","pure_quanta","I55";
;
PART_NUMBER"TMP_QCH21006JB10"
MATERIAL"EMPTY"
TOLERANCE"5%"
VOLTAGE"50V"
VALUE"1000PF"
PACK_TYPE"0402"
$LOCATION"C2267"
CDS_LIB"pure_quanta"
CDS_LOCATION"C2267"
$SEC"1"
CDS_SEC"1";
"B"
$PN"2"45;
"A"
$PN"1"73;
%"UNIVERSAL_GND"
"1","(5425,3850)","0","logical_power","I56";
;
HDL_POWER"GND"
CDS_LIB"logical_power";
"A"45;
%"Q_CAP"
"1","(5450,2675)","0","pure_quanta","I57";
;
PART_NUMBER"TMP_QCH21006JB10"
MATERIAL"EMPTY"
TOLERANCE"5%"
VOLTAGE"50V"
VALUE"1000PF"
PACK_TYPE"0402"
$LOCATION"C2269"
CDS_LIB"pure_quanta"
CDS_LOCATION"C2269"
$SEC"1"
CDS_SEC"1";
"B"
$PN"2"46;
"A"
$PN"1"66;
%"UNIVERSAL_GND"
"1","(5450,2475)","0","logical_power","I58";
;
HDL_POWER"GND"
CDS_LIB"logical_power";
"A"46;
%"UNIVERSAL_POWER"
"1","(4675,3375)","0","logical_power","I59";
;
HDL_POWER"P3V3_AUX"
CDS_LIB"logical_power";
"A"12;
%"MOSFET_NCH_DUAL"
"2","(-25,3800)","0","pure_quanta","I6";
;
PART_NUMBER"BAM138K0003"
PART_TYPE"SMLF"
VALUE"PJT138K"
MATERIAL"IC"
LOCATION"Q128"
CDS_LMAN_SYM_OUTLINE"-150,150,150,-150"
NEEDS_NO_SIZE"TRUE"
CDS_LIB"pure_quanta"
$SEC"2"
CDS_SEC"2";
"S2"
$PN"4"53;
"G2"
$PN"5"70;
"D2"
$PN"3"57;
%"Q_RES"
"2","(4675,3150)","0","pure_quanta","I60";
;
PART_NUMBER"CS24702JB10"
PACK_TYPE"0402LF"
VALUE"4.7K"
TOLERANCE"5%"
WATTAGE"1/16W"
MATERIAL"CHIP"
$LOCATION"R4142"
CDS_LIB"pure_quanta"
CDS_LOCATION"R4142"
$SEC"1"
CDS_SEC"1";
"A"
$PN"1"12;
"B"
$PN"2"66;
%"UNIVERSAL_POWER"
"1","(4650,1925)","0","logical_power","I62";
;
HDL_POWER"P3V3_AUX"
CDS_LIB"logical_power";
"A"11;
%"UNIVERSAL_GND"
"1","(4675,2350)","0","logical_power","I63";
;
HDL_POWER"GND"
CDS_LIB"logical_power";
"A"47;
%"Q_RES"
"2","(4650,1700)","0","pure_quanta","I64";
;
PART_NUMBER"CS24702JB10"
MATERIAL"CHIP"
WATTAGE"1/16W"
PACK_TYPE"0402LF"
TOLERANCE"5%"
VALUE"4.7K"
$LOCATION"R4141"
CDS_LIB"pure_quanta"
CDS_LOCATION"R4141"
$SEC"1"
CDS_SEC"1";
"A"
$PN"1"11;
"B"
$PN"2"74;
%"UNIVERSAL_GND"
"1","(5425,1025)","0","logical_power","I65";
;
CDS_LIB"logical_power"
HDL_POWER"GND";
"A"32;
%"Q_CAP"
"1","(5425,1225)","0","pure_quanta","I66";
;
PART_NUMBER"TMP_QCH21006JB10"
VOLTAGE"50V"
TOLERANCE"5%"
PACK_TYPE"0402"
VALUE"1000PF"
MATERIAL"EMPTY"
$LOCATION"C2268"
CDS_LIB"pure_quanta"
CDS_LOCATION"C2268"
$SEC"1"
CDS_SEC"1";
"B"
$PN"2"32;
"A"
$PN"1"74;
%"UNIVERSAL_GND"
"1","(4650,900)","0","logical_power","I67";
;
CDS_LIB"logical_power"
HDL_POWER"GND";
"A"31;
%"UNIVERSAL_GND"
"1","(4650,3725)","0","logical_power","I68";
;
HDL_POWER"GND"
CDS_LIB"logical_power";
"A"48;
%"UNIVERSAL_POWER"
"1","(3500,4625)","0","logical_power","I69";
;
HDL_POWER"P3V3_AUX"
CDS_LIB"logical_power";
"A"7;
%"UNIVERSAL_GND"
"1","(25,3425)","0","logical_power","I7";
;
CDS_LIB"logical_power"
HDL_POWER"GND";
"A"53;
%"MOSFET_NCH_DUAL"
"2","(4600,4100)","0","pure_quanta","I70";
;
PART_NUMBER"BAM138K0003"
PART_TYPE"SMLF"
VALUE"PJT138K"
MATERIAL"IC"
$LOCATION"Q130"
CDS_LMAN_SYM_OUTLINE"-150,150,150,-150"
NEEDS_NO_SIZE"TRUE"
CDS_LIB"pure_quanta"
CDS_LOCATION"Q130"
$SEC"2"
CDS_SEC"2";
"S2"
$PN"4"48;
"G2"
$PN"5"76;
"D2"
$PN"3"73;
%"MOSFET_NCH_DUAL"
"2","(4625,2725)","0","pure_quanta","I71";
;
PART_NUMBER"BAM138K0003"
VALUE"PJT138K"
PART_TYPE"SMLF"
MATERIAL"IC"
LOCATION"Q133"
CDS_LIB"pure_quanta"
NEEDS_NO_SIZE"TRUE"
CDS_LMAN_SYM_OUTLINE"-150,150,150,-150"
$SEC"2"
CDS_SEC"2";
"S2"
$PN"4"47;
"G2"
$PN"5"67;
"D2"
$PN"3"66;
%"Q_RES"
"2","(3500,4400)","0","pure_quanta","I72";
;
PART_NUMBER"CS24702JB10"
TOLERANCE"5%"
VALUE"4.7K"
WATTAGE"1/16W"
PACK_TYPE"0402LF"
MATERIAL"CHIP"
$LOCATION"R4137"
CDS_LIB"pure_quanta"
CDS_LOCATION"R4137"
$SEC"1"
CDS_SEC"1";
"A"
$PN"1"7;
"B"
$PN"2"76;
%"UNIVERSAL_GND"
"1","(3500,3425)","0","logical_power","I73";
;
HDL_POWER"GND"
CDS_LIB"logical_power";
"A"49;
%"MOSFET_NCH_DUAL"
"1","(3450,3800)","0","pure_quanta","I74";
;
PART_NUMBER"BAM138K0003"
MATERIAL"IC"
PART_TYPE"SMLF"
VALUE"PJT138K"
LOCATION"Q130"
CDS_LMAN_SYM_OUTLINE"-150,150,150,-150"
NEEDS_NO_SIZE"TRUE"
CDS_LIB"pure_quanta"
$SEC"1"
CDS_SEC"1";
"D1"
$PN"6"76;
"G1"
$PN"2"58;
"S1"
$PN"1"49;
%"UNIVERSAL_POWER"
"1","(3525,3250)","0","logical_power","I75";
;
HDL_POWER"P3V3_AUX"
CDS_LIB"logical_power";
"A"6;
%"Q_RES"
"2","(3525,3025)","0","pure_quanta","I76";
;
PART_NUMBER"CS24702JB10"
WATTAGE"1/16W"
TOLERANCE"5%"
PACK_TYPE"0402LF"
VALUE"4.7K"
MATERIAL"CHIP"
$LOCATION"R4139"
CDS_LIB"pure_quanta"
CDS_LOCATION"R4139"
$SEC"1"
CDS_SEC"1";
"A"
$PN"1"6;
"B"
$PN"2"67;
%"MOSFET_NCH_DUAL"
"2","(4600,1275)","0","pure_quanta","I77";
;
PART_NUMBER"BAM138K0003"
MATERIAL"IC"
PART_TYPE"SMLF"
VALUE"PJT138K"
$LOCATION"Q129"
CDS_LMAN_SYM_OUTLINE"-150,150,150,-150"
NEEDS_NO_SIZE"TRUE"
CDS_LIB"pure_quanta"
CDS_LOCATION"Q129"
$SEC"2"
CDS_SEC"2";
"S2"
$PN"4"31;
"G2"
$PN"5"75;
"D2"
$PN"3"74;
%"MOSFET_NCH_DUAL"
"1","(3475,2425)","0","pure_quanta","I78";
;
PART_NUMBER"BAM138K0003"
PART_TYPE"SMLF"
VALUE"PJT138K"
MATERIAL"IC"
$LOCATION"Q133"
CDS_LMAN_SYM_OUTLINE"-150,150,150,-150"
NEEDS_NO_SIZE"TRUE"
CDS_LIB"pure_quanta"
CDS_LOCATION"Q133"
$SEC"1"
CDS_SEC"1";
"D1"
$PN"6"67;
"G1"
$PN"2"59;
"S1"
$PN"1"50;
%"UNIVERSAL_GND"
"1","(3525,2050)","0","logical_power","I79";
;
HDL_POWER"GND"
CDS_LIB"logical_power";
"A"50;
%"UNIVERSAL_POWER"
"1","(-1125,4325)","0","logical_power","I8";
;
HDL_POWER"P3V3_AUX"
CDS_LIB"logical_power";
"A"14;
%"UNIVERSAL_POWER"
"1","(3500,1800)","0","logical_power","I80";
;
HDL_POWER"P3V3_AUX"
CDS_LIB"logical_power";
"A"8;
%"Q_RES"
"2","(3500,1575)","0","pure_quanta","I81";
;
PART_NUMBER"CS24702JB10"
MATERIAL"CHIP"
WATTAGE"1/16W"
PACK_TYPE"0402LF"
TOLERANCE"5%"
VALUE"4.7K"
$LOCATION"R4138"
CDS_LIB"pure_quanta"
CDS_LOCATION"R4138"
$SEC"1"
CDS_SEC"1";
"A"
$PN"1"8;
"B"
$PN"2"75;
%"UNIVERSAL_GND"
"1","(3500,600)","0","logical_power","I82";
;
CDS_LIB"logical_power"
HDL_POWER"GND";
"A"30;
%"MOSFET_NCH_DUAL"
"1","(3450,975)","0","pure_quanta","I83";
;
PART_NUMBER"BAM138K0003"
MATERIAL"IC"
VALUE"PJT138K"
PART_TYPE"SMLF"
LOCATION"Q129"
CDS_LIB"pure_quanta"
NEEDS_NO_SIZE"TRUE"
CDS_LMAN_SYM_OUTLINE"-150,150,150,-150"
$SEC"1"
CDS_SEC"1";
"D1"
$PN"6"75;
"G1"
$PN"2"60;
"S1"
$PN"1"30;
%"UNIVERSAL_POWER"
"1","(2325,4275)","0","logical_power","I84";
;
HDL_POWER"P3V3_AUX"
CDS_LIB"logical_power";
"A"16;
%"Q_RES"
"2","(2325,4025)","0","pure_quanta","I85";
;
PART_NUMBER"CS35492FB03"
TOLERANCE"1%"
VALUE"54.9K"
PACK_TYPE"0402LF"
MATERIAL"EMPTY"
WATTAGE"1/16W"
$LOCATION"R4131"
CDS_LIB"pure_quanta"
CDS_LOCATION"R4131"
$SEC"1"
CDS_SEC"1";
"A"
$PN"1"16;
"B"
$PN"2"58;
%"Q_RES"
"2","(2350,3550)","0","pure_quanta","I86";
;
PART_NUMBER"CS41002FB09"
WATTAGE"1/16W"
TOLERANCE"1%"
VALUE"100K"
MATERIAL"EMPTY"
PACK_TYPE"0402LF"
$LOCATION"R4132"
CDS_LIB"pure_quanta"
CDS_LOCATION"R4132"
$SEC"1"
CDS_SEC"1";
"A"
$PN"1"58;
"B"
$PN"2"33;
%"UNIVERSAL_GND"
"1","(2350,3275)","0","logical_power","I88";
;
HDL_POWER"GND"
CDS_LIB"logical_power";
"A"33;
%"UNIVERSAL_POWER"
"1","(2350,2900)","0","logical_power","I89";
;
HDL_POWER"P3V3_AUX"
CDS_LIB"logical_power";
"A"1;
%"Q_RES"
"2","(-1125,4100)","0","pure_quanta","I9";
;
PART_NUMBER"CS24702JB10"
VALUE"4.7K"
TOLERANCE"5%"
WATTAGE"1/16W"
MATERIAL"CHIP"
PACK_TYPE"0402LF"
$LOCATION"R4125"
CDS_LIB"pure_quanta"
CDS_LOCATION"R4125"
$SEC"1"
CDS_SEC"1";
"A"
$PN"1"14;
"B"
$PN"2"70;
%"Q_RES"
"2","(2375,2175)","0","pure_quanta","I91";
;
PART_NUMBER"CS41002FB09"
MATERIAL"EMPTY"
PACK_TYPE"0402LF"
WATTAGE"1/16W"
VALUE"100K"
TOLERANCE"1%"
$LOCATION"R4136"
CDS_LIB"pure_quanta"
CDS_LOCATION"R4136"
$SEC"1"
CDS_SEC"1";
"A"
$PN"1"59;
"B"
$PN"2"34;
%"UNIVERSAL_GND"
"1","(2375,1900)","0","logical_power","I92";
;
HDL_POWER"GND"
CDS_LIB"logical_power";
"A"34;
%"UNIVERSAL_POWER"
"1","(2325,1450)","0","logical_power","I93";
;
HDL_POWER"P3V3_AUX"
CDS_LIB"logical_power";
"A"23;
%"Q_RES"
"2","(2325,1200)","0","pure_quanta","I95";
;
PART_NUMBER"CS35492FB03"
VALUE"54.9K"
TOLERANCE"1%"
PACK_TYPE"0402LF"
MATERIAL"EMPTY"
WATTAGE"1/16W"
$LOCATION"R4133"
CDS_LIB"pure_quanta"
CDS_LOCATION"R4133"
$SEC"1"
CDS_SEC"1";
"A"
$PN"1"23;
"B"
$PN"2"60;
%"Q_RES"
"2","(2350,725)","0","pure_quanta","I96";
;
PART_NUMBER"CS41002FB09"
WATTAGE"1/16W"
PACK_TYPE"0402LF"
TOLERANCE"1%"
MATERIAL"EMPTY"
VALUE"100K"
$LOCATION"R4134"
CDS_LIB"pure_quanta"
CDS_LOCATION"R4134"
$SEC"1"
CDS_SEC"1";
"A"
$PN"1"60;
"B"
$PN"2"29;
%"UNIVERSAL_GND"
"1","(2350,450)","0","logical_power","I97";
;
CDS_LIB"logical_power"
HDL_POWER"GND";
"A"29;
%"MOSFET_NCH_DUAL"
"1","(-1100,-875)","0","pure_quanta","I99";
;
PART_NUMBER"BAM138K0003"
PART_TYPE"SMLF"
MATERIAL"IC"
VALUE"PJT138K"
$LOCATION"Q134"
CDS_LIB"pure_quanta"
NEEDS_NO_SIZE"TRUE"
CDS_LMAN_SYM_OUTLINE"-150,150,150,-150"
CDS_LOCATION"Q134"
$SEC"1"
CDS_SEC"1";
"D1"
$PN"6"65;
"G1"
$PN"2"64;
"S1"
$PN"1"41;
END.
